(kicad_pcb
	(version 20241229)
	(generator "pcbnew")
	(generator_version "9.0")
	(general
		(thickness 1.61)
		(legacy_teardrops no)
	)
	(paper "A3")
	(title_block
		(title "SO-DIMM DDR5 Tester")
		(date "2025-11-26")
		(rev "1.3.0")
		(comment 9 "footprint 59 of 627 (U4), pads 501-576 of 676")
	)
	(layers
		(0 "F.Cu" signal)
		(4 "In1.Cu" power)
		(6 "In2.Cu" mixed)
		(8 "In3.Cu" power)
		(10 "In4.Cu" mixed)
		(12 "In5.Cu" power)
		(14 "In6.Cu" mixed)
		(16 "In7.Cu" power)
		(18 "In8.Cu" power)
		(20 "In9.Cu" mixed)
		(22 "In10.Cu" power)
		(2 "B.Cu" signal)
		(9 "F.Adhes" user "F.Adhesive")
		(11 "B.Adhes" user "B.Adhesive")
		(13 "F.Paste" user)
		(15 "B.Paste" user)
		(5 "F.SilkS" user "F.Silkscreen")
		(7 "B.SilkS" user "B.Silkscreen")
		(1 "F.Mask" user)
		(3 "B.Mask" user)
		(17 "Dwgs.User" user "User.Drawings")
		(19 "Cmts.User" user "User.Comments")
		(21 "Eco1.User" user "User.Eco1")
		(23 "Eco2.User" user "User.Eco2")
		(25 "Edge.Cuts" user)
		(27 "Margin" user)
		(31 "F.CrtYd" user "F.Courtyard")
		(29 "B.CrtYd" user "B.Courtyard")
		(35 "F.Fab" user)
		(33 "B.Fab" user)
	)
	(footprint "antmicro-footprints:BGA-676_27x27mm_Layout26x26_P1x1mm_FFG676"
		(layer "F.Cu")
		(at 138.875501 174.801 180)
		(descr "FPGA XC7K160TFBG676")
		(tags "FPGA XC7K160TFBG676")
		(property "Reference" "U4"
			(at -12.224499 14.051 180)
			(layer "F.SilkS")
			(effects
				(font
					(size 0.7 0.7)
					(thickness 0.15)
				)
				(justify left bottom)
			)
		)
		(property "Value" "XC7K160T-FFG676"
			(at 0 15.5 180)
			(layer "F.Fab")
			(effects
				(font
					(size 0.7 0.7)
					(thickness 0.15)
				)
				(justify left bottom)
			)
		)
		(property "Datasheet" "https://docs.xilinx.com/v/u/en-US/ds180_7Series_Overview"
			(at 0 0 180)
			(layer "F.Fab")
			(hide yes)
			(effects
				(font
					(size 1.27 1.27)
					(thickness 0.15)
				)
			)
		)
		(property "Author" "Antmicro"
			(at 277.751002 349.602 0)
			(layer "F.Fab")
			(hide yes)
			(effects
				(font
					(size 1 1)
					(thickness 0.15)
				)
			)
		)
		(property "License" "Apache-2.0"
			(at 277.751002 349.602 0)
			(layer "F.Fab")
			(hide yes)
			(effects
				(font
					(size 1 1)
					(thickness 0.15)
				)
			)
		)
		(property "MPN" "XC7K160T-FFG676"
			(at 277.751002 349.602 0)
			(layer "F.Fab")
			(hide yes)
			(effects
				(font
					(size 1 1)
					(thickness 0.15)
				)
			)
		)
		(property "Manufacturer" "AMD-Xilinx"
			(at 277.751002 349.602 0)
			(layer "F.Fab")
			(hide yes)
			(effects
				(font
					(size 1 1)
					(thickness 0.15)
				)
			)
		)
		(sheetname "/FPGA Config/")
		(sheetfile "fpga-config.kicad_sch")
		(attr smd)
		(pad "P7" smd circle
			(at -6.5 0.499 180)
			(size 0.5 0.5)
			(layers "F.Cu" "F.Mask" "F.Paste")
			(net 635 "/FPGA Config/CFGBVS")
			(pinfunction "CFGBVS_0")
			(pintype "bidirectional")
			(die_length 14.171)
		)
		(pad "P8" smd circle
			(at -5.5 0.499 180)
			(size 0.5 0.5)
			(layers "F.Cu" "F.Mask" "F.Paste")
			(net 188 "+1V8")
			(pinfunction "VCCAUX_IO_G0")
			(pintype "power_in")
		)
		(pad "P9" smd circle
			(at -4.5 0.499 180)
			(size 0.5 0.5)
			(layers "F.Cu" "F.Mask" "F.Paste")
			(net 1 "GND")
			(pinfunction "GND")
			(pintype "passive")
		)
		(pad "P10" smd circle
			(at -3.5 0.499 180)
			(size 0.5 0.5)
			(layers "F.Cu" "F.Mask" "F.Paste")
			(net 188 "+1V8")
			(pinfunction "VCCAUX")
			(pintype "passive")
		)
		(pad "P11" smd circle
			(at -2.5 0.499 180)
			(size 0.5 0.5)
			(layers "F.Cu" "F.Mask" "F.Paste")
			(net 1 "GND")
			(pinfunction "VN_0")
			(pintype "bidirectional")
			(die_length 13.84)
		)
		(pad "P12" smd circle
			(at -1.5 0.499 180)
			(size 0.5 0.5)
			(layers "F.Cu" "F.Mask" "F.Paste")
			(net 1 "GND")
			(pinfunction "VREFP_0")
			(pintype "bidirectional")
			(die_length 12.633)
		)
		(pad "P13" smd circle
			(at -0.5 0.499 180)
			(size 0.5 0.5)
			(layers "F.Cu" "F.Mask" "F.Paste")
			(net 1 "GND")
			(pinfunction "GND")
			(pintype "passive")
		)
		(pad "P14" smd circle
			(at 0.499 0.499 180)
			(size 0.5 0.5)
			(layers "F.Cu" "F.Mask" "F.Paste")
			(net 227 "+1V0")
			(pinfunction "VCCINT")
			(pintype "passive")
		)
		(pad "P15" smd circle
			(at 1.499 0.499 180)
			(size 0.5 0.5)
			(layers "F.Cu" "F.Mask" "F.Paste")
			(net 1 "GND")
			(pinfunction "GND")
			(pintype "passive")
		)
		(pad "P16" smd circle
			(at 2.499 0.499 180)
			(size 0.5 0.5)
			(layers "F.Cu" "F.Mask" "F.Paste")
			(net 538 "unconnected-(U4B-IO_L20P_T3_13-PadP16)")
			(pinfunction "IO_L20P_T3_13")
			(pintype "bidirectional+no_connect")
			(die_length 8.016)
		)
		(pad "P17" smd circle
			(at 3.499 0.499 180)
			(size 0.5 0.5)
			(layers "F.Cu" "F.Mask" "F.Paste")
			(net 1 "GND")
			(pinfunction "GND")
			(pintype "passive")
		)
		(pad "P18" smd circle
			(at 4.499 0.499 180)
			(size 0.5 0.5)
			(layers "F.Cu" "F.Mask" "F.Paste")
			(net 539 "unconnected-(U4B-IO_L24N_T3_13-PadP18)")
			(pinfunction "IO_L24N_T3_13")
			(pintype "bidirectional+no_connect")
			(die_length 10.217)
		)
		(pad "P19" smd circle
			(at 5.499 0.499 180)
			(size 0.5 0.5)
			(layers "F.Cu" "F.Mask" "F.Paste")
			(net 540 "unconnected-(U4B-IO_L9P_T1_DQS_13-PadP19)")
			(pinfunction "IO_L9P_T1_DQS_13")
			(pintype "bidirectional+no_connect")
			(die_length 12.118)
		)
		(pad "P20" smd circle
			(at 6.499 0.499 180)
			(size 0.5 0.5)
			(layers "F.Cu" "F.Mask" "F.Paste")
			(net 541 "unconnected-(U4B-IO_L9N_T1_DQS_13-PadP20)")
			(pinfunction "IO_L9N_T1_DQS_13")
			(pintype "bidirectional+no_connect")
			(die_length 12.121)
		)
		(pad "P21" smd circle
			(at 7.499 0.499 180)
			(size 0.5 0.5)
			(layers "F.Cu" "F.Mask" "F.Paste")
			(net 542 "unconnected-(U4B-IO_L13N_T2_MRCC_13-PadP21)")
			(pinfunction "IO_L13N_T2_MRCC_13")
			(pintype "bidirectional+no_connect")
			(die_length 10.375)
		)
		(pad "P22" smd circle
			(at 8.499 0.499 180)
			(size 0.5 0.5)
			(layers "F.Cu" "F.Mask" "F.Paste")
			(net 376 "Net-(R96-Pad2)")
			(pinfunction "VCCO_13")
			(pintype "passive")
		)
		(pad "P23" smd circle
			(at 9.499 0.499 180)
			(size 0.5 0.5)
			(layers "F.Cu" "F.Mask" "F.Paste")
			(net 543 "unconnected-(U4B-IO_L11P_T1_SRCC_13-PadP23)")
			(pinfunction "IO_L11P_T1_SRCC_13")
			(pintype "bidirectional+no_connect")
			(die_length 14.144)
		)
		(pad "P24" smd circle
			(at 10.499 0.499 180)
			(size 0.5 0.5)
			(layers "F.Cu" "F.Mask" "F.Paste")
			(net 544 "unconnected-(U4B-IO_L4P_T0_13-PadP24)")
			(pinfunction "IO_L4P_T0_13")
			(pintype "bidirectional+no_connect")
			(die_length 13.362)
		)
		(pad "P25" smd circle
			(at 11.499 0.499 180)
			(size 0.5 0.5)
			(layers "F.Cu" "F.Mask" "F.Paste")
			(net 545 "unconnected-(U4B-IO_L6N_T0_VREF_13-PadP25)")
			(pinfunction "IO_L6N_T0_VREF_13")
			(pintype "bidirectional+no_connect")
			(die_length 14.662)
		)
		(pad "P26" smd circle
			(at 12.499 0.499 180)
			(size 0.5 0.5)
			(layers "F.Cu" "F.Mask" "F.Paste")
			(net 546 "unconnected-(U4B-IO_L2N_T0_13-PadP26)")
			(pinfunction "IO_L2N_T0_13")
			(pintype "bidirectional+no_connect")
			(die_length 17.56)
		)
		(pad "R1" smd circle
			(at -12.5 1.499 180)
			(size 0.5 0.5)
			(layers "F.Cu" "F.Mask" "F.Paste")
			(net 1 "GND")
			(pinfunction "GND")
			(pintype "passive")
		)
		(pad "R2" smd circle
			(at -11.5 1.499 180)
			(size 0.5 0.5)
			(layers "F.Cu" "F.Mask" "F.Paste")
			(net 1 "GND")
			(pinfunction "GND")
			(pintype "passive")
		)
		(pad "R3" smd circle
			(at -10.5 1.499 180)
			(size 0.5 0.5)
			(layers "F.Cu" "F.Mask" "F.Paste")
			(net 547 "unconnected-(U4I-MGTXRXN0_115-PadR3)")
			(pinfunction "MGTXRXN0_115")
			(pintype "bidirectional+no_connect")
			(die_length 13.691)
		)
		(pad "R4" smd circle
			(at -9.5 1.499 180)
			(size 0.5 0.5)
			(layers "F.Cu" "F.Mask" "F.Paste")
			(net 548 "unconnected-(U4I-MGTXRXP0_115-PadR4)")
			(pinfunction "MGTXRXP0_115")
			(pintype "bidirectional+no_connect")
			(die_length 13.771)
		)
		(pad "R5" smd circle
			(at -8.5 1.499 180)
			(size 0.5 0.5)
			(layers "F.Cu" "F.Mask" "F.Paste")
			(net 1 "GND")
			(pinfunction "GND")
			(pintype "passive")
		)
		(pad "R6" smd circle
			(at -7.5 1.499 180)
			(size 0.5 0.5)
			(layers "F.Cu" "F.Mask" "F.Paste")
			(net 48 "/Debug FTDI/JTAG.TDI")
			(pinfunction "TDI_0")
			(pintype "bidirectional")
			(die_length 16.338)
		)
		(pad "R7" smd circle
			(at -6.5 1.499 180)
			(size 0.5 0.5)
			(layers "F.Cu" "F.Mask" "F.Paste")
			(net 47 "/Debug FTDI/JTAG.TDO")
			(pinfunction "TDO_0")
			(pintype "bidirectional")
			(die_length 15.018)
		)
		(pad "R8" smd circle
			(at -5.5 1.499 180)
			(size 0.5 0.5)
			(layers "F.Cu" "F.Mask" "F.Paste")
			(net 1 "GND")
			(pinfunction "GND")
			(pintype "passive")
		)
		(pad "R9" smd circle
			(at -4.5 1.499 180)
			(size 0.5 0.5)
			(layers "F.Cu" "F.Mask" "F.Paste")
			(net 188 "+1V8")
			(pinfunction "VCCAUX_IO_G0")
			(pintype "passive")
		)
		(pad "R10" smd circle
			(at -3.5 1.499 180)
			(size 0.5 0.5)
			(layers "F.Cu" "F.Mask" "F.Paste")
			(net 1 "GND")
			(pinfunction "GND")
			(pintype "passive")
		)
		(pad "R11" smd circle
			(at -2.5 1.499 180)
			(size 0.5 0.5)
			(layers "F.Cu" "F.Mask" "F.Paste")
			(net 1 "GND")
			(pinfunction "DXN_0")
			(pintype "bidirectional")
			(die_length 14.9)
		)
		(pad "R12" smd circle
			(at -1.5 1.499 180)
			(size 0.5 0.5)
			(layers "F.Cu" "F.Mask" "F.Paste")
			(net 1 "GND")
			(pinfunction "DXP_0")
			(pintype "bidirectional")
			(die_length 12.842)
		)
		(pad "R13" smd circle
			(at -0.5 1.499 180)
			(size 0.5 0.5)
			(layers "F.Cu" "F.Mask" "F.Paste")
			(net 227 "+1V0")
			(pinfunction "VCCBRAM")
			(pintype "passive")
		)
		(pad "R14" smd circle
			(at 0.499 1.499 180)
			(size 0.5 0.5)
			(layers "F.Cu" "F.Mask" "F.Paste")
			(net 1 "GND")
			(pinfunction "GND")
			(pintype "passive")
		)
		(pad "R15" smd circle
			(at 1.499 1.499 180)
			(size 0.5 0.5)
			(layers "F.Cu" "F.Mask" "F.Paste")
			(net 227 "+1V0")
			(pinfunction "VCCINT")
			(pintype "passive")
		)
		(pad "R16" smd circle
			(at 2.499 1.499 180)
			(size 0.5 0.5)
			(layers "F.Cu" "F.Mask" "F.Paste")
			(net 549 "unconnected-(U4B-IO_L21P_T3_DQS_13-PadR16)")
			(pinfunction "IO_L21P_T3_DQS_13")
			(pintype "bidirectional+no_connect")
			(die_length 10.096)
		)
		(pad "R17" smd circle
			(at 3.499 1.499 180)
			(size 0.5 0.5)
			(layers "F.Cu" "F.Mask" "F.Paste")
			(net 550 "unconnected-(U4B-IO_L21N_T3_DQS_13-PadR17)")
			(pinfunction "IO_L21N_T3_DQS_13")
			(pintype "bidirectional+no_connect")
			(die_length 10.012)
		)
		(pad "R18" smd circle
			(at 4.499 1.499 180)
			(size 0.5 0.5)
			(layers "F.Cu" "F.Mask" "F.Paste")
			(net 551 "unconnected-(U4B-IO_L24P_T3_13-PadR18)")
			(pinfunction "IO_L24P_T3_13")
			(pintype "bidirectional+no_connect")
			(die_length 8.982)
		)
		(pad "R19" smd circle
			(at 5.499 1.499 180)
			(size 0.5 0.5)
			(layers "F.Cu" "F.Mask" "F.Paste")
			(net 376 "Net-(R96-Pad2)")
			(pinfunction "VCCO_13")
			(pintype "passive")
		)
		(pad "R20" smd circle
			(at 6.499 1.499 180)
			(size 0.5 0.5)
			(layers "F.Cu" "F.Mask" "F.Paste")
			(net 552 "unconnected-(U4B-IO_L16N_T2_13-PadR20)")
			(pinfunction "IO_L16N_T2_13")
			(pintype "bidirectional+no_connect")
			(die_length 9.979)
		)
		(pad "R21" smd circle
			(at 7.499 1.499 180)
			(size 0.5 0.5)
			(layers "F.Cu" "F.Mask" "F.Paste")
			(net 553 "unconnected-(U4B-IO_L13P_T2_MRCC_13-PadR21)")
			(pinfunction "IO_L13P_T2_MRCC_13")
			(pintype "bidirectional+no_connect")
			(die_length 10.23)
		)
		(pad "R22" smd circle
			(at 8.499 1.499 180)
			(size 0.5 0.5)
			(layers "F.Cu" "F.Mask" "F.Paste")
			(net 554 "unconnected-(U4B-IO_L14P_T2_SRCC_13-PadR22)")
			(pinfunction "IO_L14P_T2_SRCC_13")
			(pintype "bidirectional+no_connect")
			(die_length 11.973)
		)
		(pad "R23" smd circle
			(at 9.499 1.499 180)
			(size 0.5 0.5)
			(layers "F.Cu" "F.Mask" "F.Paste")
			(net 555 "unconnected-(U4B-IO_L14N_T2_SRCC_13-PadR23)")
			(pinfunction "IO_L14N_T2_SRCC_13")
			(pintype "bidirectional+no_connect")
			(die_length 12.182)
		)
		(pad "R24" smd circle
			(at 10.499 1.499 180)
			(size 0.5 0.5)
			(layers "F.Cu" "F.Mask" "F.Paste")
			(net 1 "GND")
			(pinfunction "GND")
			(pintype "passive")
		)
		(pad "R25" smd circle
			(at 11.499 1.499 180)
			(size 0.5 0.5)
			(layers "F.Cu" "F.Mask" "F.Paste")
			(net 556 "unconnected-(U4B-IO_L6P_T0_13-PadR25)")
			(pinfunction "IO_L6P_T0_13")
			(pintype "bidirectional+no_connect")
			(die_length 14.416)
		)
		(pad "R26" smd circle
			(at 12.499 1.499 180)
			(size 0.5 0.5)
			(layers "F.Cu" "F.Mask" "F.Paste")
			(net 557 "unconnected-(U4B-IO_L2P_T0_13-PadR26)")
			(pinfunction "IO_L2P_T0_13")
			(pintype "bidirectional+no_connect")
			(die_length 16.3)
		)
		(pad "T1" smd circle
			(at -12.5 2.499 180)
			(size 0.5 0.5)
			(layers "F.Cu" "F.Mask" "F.Paste")
			(net 1 "GND")
			(pinfunction "GND")
			(pintype "passive")
		)
		(pad "T2" smd circle
			(at -11.5 2.499 180)
			(size 0.5 0.5)
			(layers "F.Cu" "F.Mask" "F.Paste")
			(net 632 "/FPGA Config/MODE1")
			(pinfunction "M1_0")
			(pintype "bidirectional")
			(die_length 22.574)
		)
		(pad "T3" smd circle
			(at -10.5 2.499 180)
			(size 0.5 0.5)
			(layers "F.Cu" "F.Mask" "F.Paste")
			(net 1 "GND")
			(pinfunction "GND")
			(pintype "passive")
		)
		(pad "T4" smd circle
			(at -9.5 2.499 180)
			(size 0.5 0.5)
			(layers "F.Cu" "F.Mask" "F.Paste")
			(net 1 "GND")
			(pinfunction "GND")
			(pintype "passive")
		)
		(pad "T5" smd circle
			(at -8.5 2.499 180)
			(size 0.5 0.5)
			(layers "F.Cu" "F.Mask" "F.Paste")
			(net 633 "/FPGA Config/MODE0")
			(pinfunction "M0_0")
			(pintype "bidirectional")
			(die_length 20.855)
		)
		(pad "T6" smd circle
			(at -7.5 2.499 180)
			(size 0.5 0.5)
			(layers "F.Cu" "F.Mask" "F.Paste")
			(net 200 "+3V3")
			(pinfunction "VCCO_0")
			(pintype "passive")
		)
		(pad "T7" smd circle
			(at -6.5 2.499 180)
			(size 0.5 0.5)
			(layers "F.Cu" "F.Mask" "F.Paste")
			(net 193 "/DDR5 SODIMM/B.CB3")
			(pinfunction "IO_25_VRP_34")
			(pintype "bidirectional")
			(die_length 9.857)
		)
		(pad "T8" smd circle
			(at -5.5 2.499 180)
			(size 0.5 0.5)
			(layers "F.Cu" "F.Mask" "F.Paste")
			(net 188 "+1V8")
			(pinfunction "VCCAUX_IO_G0")
			(pintype "passive")
		)
		(pad "T9" smd circle
			(at -4.5 2.499 180)
			(size 0.5 0.5)
			(layers "F.Cu" "F.Mask" "F.Paste")
			(net 1 "GND")
			(pinfunction "GND")
			(pintype "passive")
		)
		(pad "T10" smd circle
			(at -3.5 2.499 180)
			(size 0.5 0.5)
			(layers "F.Cu" "F.Mask" "F.Paste")
			(net 188 "+1V8")
			(pinfunction "VCCAUX")
			(pintype "passive")
		)
		(pad "T11" smd circle
			(at -2.5 2.499 180)
			(size 0.5 0.5)
			(layers "F.Cu" "F.Mask" "F.Paste")
			(net 1 "GND")
			(pinfunction "GND")
			(pintype "passive")
		)
		(pad "T12" smd circle
			(at -1.5 2.499 180)
			(size 0.5 0.5)
			(layers "F.Cu" "F.Mask" "F.Paste")
			(net 227 "+1V0")
			(pinfunction "VCCBRAM")
			(pintype "passive")
		)
		(pad "T13" smd circle
			(at -0.5 2.499 180)
			(size 0.5 0.5)
			(layers "F.Cu" "F.Mask" "F.Paste")
			(net 1 "GND")
			(pinfunction "GND")
			(pintype "passive")
		)
		(pad "T14" smd circle
			(at 0.499 2.499 180)
			(size 0.5 0.5)
			(layers "F.Cu" "F.Mask" "F.Paste")
			(net 227 "+1V0")
			(pinfunction "VCCINT")
			(pintype "passive")
		)
		(pad "T15" smd circle
			(at 1.499 2.499 180)
			(size 0.5 0.5)
			(layers "F.Cu" "F.Mask" "F.Paste")
			(net 1 "GND")
			(pinfunction "GND")
			(pintype "passive")
		)
		(pad "T16" smd circle
			(at 2.499 2.499 180)
			(size 0.5 0.5)
			(layers "F.Cu" "F.Mask" "F.Paste")
			(net 376 "Net-(R96-Pad2)")
			(pinfunction "VCCO_13")
			(pintype "passive")
		)
		(pad "T17" smd circle
			(at 3.499 2.499 180)
			(size 0.5 0.5)
			(layers "F.Cu" "F.Mask" "F.Paste")
			(net 558 "unconnected-(U4B-IO_L23N_T3_13-PadT17)")
			(pinfunction "IO_L23N_T3_13")
			(pintype "bidirectional+no_connect")
			(die_length 10.353)
		)
		(pad "T18" smd circle
			(at 4.499 2.499 180)
			(size 0.5 0.5)
			(layers "F.Cu" "F.Mask" "F.Paste")
			(net 559 "unconnected-(U4B-IO_L19P_T3_13-PadT18)")
			(pinfunction "IO_L19P_T3_13")
			(pintype "bidirectional+no_connect")
			(die_length 9.92)
		)
		(pad "T19" smd circle
			(at 5.499 2.499 180)
			(size 0.5 0.5)
			(layers "F.Cu" "F.Mask" "F.Paste")
			(net 560 "unconnected-(U4B-IO_L19N_T3_VREF_13-PadT19)")
			(pinfunction "IO_L19N_T3_VREF_13")
			(pintype "bidirectional+no_connect")
			(die_length 9.055)
		)
		(pad "T20" smd circle
			(at 6.499 2.499 180)
			(size 0.5 0.5)
			(layers "F.Cu" "F.Mask" "F.Paste")
			(net 561 "unconnected-(U4B-IO_L16P_T2_13-PadT20)")
			(pinfunction "IO_L16P_T2_13")
			(pintype "bidirectional+no_connect")
			(die_length 9.491)
		)
		(pad "T21" smd circle
			(at 7.499 2.499 180)
			(size 0.5 0.5)
			(layers "F.Cu" "F.Mask" "F.Paste")
			(net 1 "GND")
			(pinfunction "GND")
			(pintype "passive")
		)
		(pad "T22" smd circle
			(at 8.499 2.499 180)
			(size 0.5 0.5)
			(layers "F.Cu" "F.Mask" "F.Paste")
			(net 562 "unconnected-(U4B-IO_L17P_T2_13-PadT22)")
			(pinfunction "IO_L17P_T2_13")
			(pintype "bidirectional+no_connect")
			(die_length 11.169)
		)
		(pad "T23" smd circle
			(at 9.499 2.499 180)
			(size 0.5 0.5)
			(layers "F.Cu" "F.Mask" "F.Paste")
			(net 563 "unconnected-(U4B-IO_L17N_T2_13-PadT23)")
			(pinfunction "IO_L17N_T2_13")
			(pintype "bidirectional+no_connect")
			(die_length 11.495)
		)
		(pad "T24" smd circle
			(at 10.499 2.499 180)
			(size 0.5 0.5)
			(layers "F.Cu" "F.Mask" "F.Paste")
			(net 564 "unconnected-(U4B-IO_L15P_T2_DQS_13-PadT24)")
			(pinfunction "IO_L15P_T2_DQS_13")
			(pintype "bidirectional+no_connect")
			(die_length 13.293)
		)
		(pad "T25" smd circle
			(at 11.499 2.499 180)
			(size 0.5 0.5)
			(layers "F.Cu" "F.Mask" "F.Paste")
			(net 565 "unconnected-(U4B-IO_L15N_T2_DQS_13-PadT25)")
			(pinfunction "IO_L15N_T2_DQS_13")
			(pintype "bidirectional+no_connect")
			(die_length 13.562)
		)
		(pad "T26" smd circle
			(at 12.499 2.499 180)
			(size 0.5 0.5)
			(layers "F.Cu" "F.Mask" "F.Paste")
			(net 376 "Net-(R96-Pad2)")
			(pinfunction "VCCO_13")
			(pintype "passive")
		)
		(pad "U1" smd circle
			(at -12.5 3.499 180)
			(size 0.5 0.5)
			(layers "F.Cu" "F.Mask" "F.Paste")
			(net 284 "/DDR5 SODIMM/B.~{DM3}")
			(pinfunction "IO_L2N_T0_34")
			(pintype "bidirectional")
			(die_length 17.749)
		)
		(pad "U2" smd circle
			(at -11.5 3.499 180)
			(size 0.5 0.5)
			(layers "F.Cu" "F.Mask" "F.Paste")
			(net 275 "/DDR5 SODIMM/B.DQ24")
			(pinfunction "IO_L2P_T0_34")
			(pintype "bidirectional")
			(die_length 16.314)
		)
		(pad "U3" smd circle
			(at -10.5 3.499 180)
			(size 0.5 0.5)
			(layers "F.Cu" "F.Mask" "F.Paste")
			(net 206 "+1V1")
			(pinfunction "VCCO_34")
			(pintype "passive")
		)
		(pad "U4" smd circle
			(at -9.5 3.499 180)
			(size 0.5 0.5)
			(layers "F.Cu" "F.Mask" "F.Paste")
			(net 192 "/DDR5 SODIMM/B.CB1")
			(pinfunction "IO_0_VRN_34")
			(pintype "bidirectional")
			(die_length 17.697)
		)
	)
)
